FILE_TYPE = MULTI_PHYS_TABLE;

PART 'MP5022CGQV_Z_QFN22'
CLASS = IC 

{========================================================================================}
:CLS_PN             = JEDEC_TYPE                      |ALT_SYMBOLS                       |DESCRIPTION                                  ;
{========================================================================================}
 'G220-10510-01'      = 'QFN26_118X197_P197_TR049X010'  |'(QFN26_118X197_P197_TR049X010)'  |'IC,MP5022C,HOTSWAP,15A,3MMX5MM,QFN-22'      

END_PART

END.

